(kicad_pcb
	(version 20260206)
	(generator "pcbnew")
	(generator_version "10.0")
	(general
		(thickness 1.6)
		(legacy_teardrops no)
	)
	(paper "A4")
	(title_block
		(title "01162023_DA0F0TEBIF0_F0T_Expander_BD_F_brd_V02_OCP.brd")
		(comment 1 "Grand Teton / footprints 6998-7003 of 9728")
	)
	(layers
		(0 "F.Cu" signal "TOP")
		(4 "In1.Cu" signal "GND")
		(6 "In2.Cu" signal "VCC")
		(8 "In3.Cu" signal "VCC1")
		(10 "In4.Cu" signal "GND1")
		(12 "In5.Cu" signal "IN1")
		(14 "In6.Cu" signal "GND2")
		(16 "In7.Cu" signal "IN2")
		(18 "In8.Cu" signal "GND3")
		(20 "In9.Cu" signal "IN3")
		(22 "In10.Cu" signal "GND4")
		(24 "In11.Cu" signal "IN4")
		(26 "In12.Cu" signal "GND5")
		(28 "In13.Cu" signal "IN5")
		(30 "In14.Cu" signal "GND6")
		(32 "In15.Cu" signal "IN6")
		(34 "In16.Cu" signal "GND7")
		(2 "B.Cu" signal "BOTTOM")
		(9 "F.Adhes" user "F.Adhesive")
		(11 "B.Adhes" user "B.Adhesive")
		(13 "F.Paste" user "Package Geometry/Pastemask Top")
		(15 "B.Paste" user "Package Geometry/Pastemask Bottom")
		(5 "F.SilkS" user "Ref Des/Silkscreen Top")
		(7 "B.SilkS" user "Ref Des/Silkscreen Bottom")
		(1 "F.Mask" user "Board Geometry/Soldermask Top")
		(3 "B.Mask" user "Board Geometry/Soldermask Bottom")
		(17 "Dwgs.User" user "User.Drawings")
		(19 "Cmts.User" user "User.Comments")
		(21 "Eco1.User" user "User.Eco1")
		(23 "Eco2.User" user "User.Eco2")
		(25 "Edge.Cuts" user "Board Geometry/Outline")
		(27 "Margin" user)
		(31 "F.CrtYd" user "Package Geometry/Place Bound Top")
		(29 "B.CrtYd" user "Package Geometry/Place Bound Bottom")
		(35 "F.Fab" user "Ref Des/Assembly Top")
		(33 "B.Fab" user "Ref Des/Assembly Bottom")
	)
	(footprint ""
		(layer "F.Cu")
		(at 46.67504 -56.977534 180)
		(property "Reference" "PC402"
			(at 0 0 180)
			(layer "F.SilkS")
			(hide yes)
			(effects
				(font
					(size 1.27 1.27)
				)
			)
		)
		(property "Value" ""
			(at 0 0 180)
			(layer "F.Fab")
			(effects
				(font
					(size 1.27 1.27)
				)
			)
		)
		(duplicate_pad_numbers_are_jumpers no)
		(fp_line
			(start 0.7874 0.4064)
			(end -0.7874 0.4064)
			(stroke
				(width 0.1524)
				(type default)
			)
			(layer "F.SilkS")
		)
		(fp_line
			(start 0.7874 -0.4064)
			(end 0.7874 0.4064)
			(stroke
				(width 0.1524)
				(type default)
			)
			(layer "F.SilkS")
		)
		(fp_line
			(start -0.7874 0.4064)
			(end -0.7874 -0.4064)
			(stroke
				(width 0.1524)
				(type default)
			)
			(layer "F.SilkS")
		)
		(fp_line
			(start -0.7874 -0.4064)
			(end 0.7874 -0.4064)
			(stroke
				(width 0.1524)
				(type default)
			)
			(layer "F.SilkS")
		)
		(fp_line
			(start 0.67945 0.3048)
			(end 0.120396 0.3048)
			(stroke
				(width 0.1)
				(type default)
			)
			(layer "F.Fab")
		)
		(fp_line
			(start 0.67945 -0.3048)
			(end 0.67945 0.3048)
			(stroke
				(width 0.1)
				(type default)
			)
			(layer "F.Fab")
		)
		(fp_line
			(start 0.12065 -0.2794)
			(end 0.12065 -0.3048)
			(stroke
				(width 0.1)
				(type default)
			)
			(layer "F.Fab")
		)
		(fp_line
			(start 0.12065 -0.3048)
			(end 0.67945 -0.3048)
			(stroke
				(width 0.1)
				(type default)
			)
			(layer "F.Fab")
		)
		(fp_line
			(start 0.120396 0.3048)
			(end 0.120396 0.2794)
			(stroke
				(width 0.1)
				(type default)
			)
			(layer "F.Fab")
		)
		(fp_line
			(start 0.120396 0.2794)
			(end -0.12065 0.2794)
			(stroke
				(width 0.1)
				(type default)
			)
			(layer "F.Fab")
		)
		(fp_line
			(start -0.12065 0.3048)
			(end -0.67945 0.3048)
			(stroke
				(width 0.1)
				(type default)
			)
			(layer "F.Fab")
		)
		(fp_line
			(start -0.12065 0.2794)
			(end -0.12065 0.3048)
			(stroke
				(width 0.1)
				(type default)
			)
			(layer "F.Fab")
		)
		(fp_line
			(start -0.12065 -0.2794)
			(end 0.12065 -0.2794)
			(stroke
				(width 0.1)
				(type default)
			)
			(layer "F.Fab")
		)
		(fp_line
			(start -0.12065 -0.305054)
			(end -0.12065 -0.2794)
			(stroke
				(width 0.1)
				(type default)
			)
			(layer "F.Fab")
		)
		(fp_line
			(start -0.67945 0.3048)
			(end -0.67945 -0.305054)
			(stroke
				(width 0.1)
				(type default)
			)
			(layer "F.Fab")
		)
		(fp_line
			(start -0.67945 -0.305054)
			(end -0.12065 -0.305054)
			(stroke
				(width 0.1)
				(type default)
			)
			(layer "F.Fab")
		)
		(pad "1" smd circle
			(at -0.40005 0 180)
			(size 0 0)
			(layers "F.Cu" "F.Mask" "F.Paste")
			(net "P12V_AUX")
		)
		(pad "2" smd circle
			(at 0.40005 0 180)
			(size 0 0)
			(layers "F.Cu" "F.Mask" "F.Paste")
			(net "GND")
		)
	)
	(footprint ""
		(layer "F.Cu")
		(at 233.800142 -194.359784)
		(property "Reference" "H69"
			(at -4.338828 -4.989322 0)
			(unlocked yes)
			(layer "F.SilkS")
			(effects
				(font
					(size 0.7874 0.5842)
					(thickness 0.1524)
				)
				(justify left)
			)
		)
		(property "Value" ""
			(at 0 0 0)
			(layer "F.Fab")
			(effects
				(font
					(size 1.27 1.27)
				)
			)
		)
		(duplicate_pad_numbers_are_jumpers no)
		(pad "1" thru_hole circle
			(at 0 0)
			(size 10.0076 10.0076)
			(drill 5.6134)
			(layers "*.Cu" "*.Mask")
			(remove_unused_layers no)
			(net "GND")
			(clearance -1.9431)
		)
	)
	(footprint ""
		(layer "F.Cu")
		(at 322.21805 -306.074572 90)
		(property "Reference" "R1371"
			(at 0 0 90)
			(layer "F.SilkS")
			(hide yes)
			(effects
				(font
					(size 1.27 1.27)
				)
			)
		)
		(property "Value" ""
			(at 0 0 90)
			(layer "F.Fab")
			(effects
				(font
					(size 1.27 1.27)
				)
			)
		)
		(duplicate_pad_numbers_are_jumpers no)
		(fp_line
			(start 0.7874 -0.4064)
			(end 0.7874 0.4064)
			(stroke
				(width 0.1524)
				(type default)
			)
			(layer "F.SilkS")
		)
		(fp_line
			(start -0.7874 -0.4064)
			(end 0.7874 -0.4064)
			(stroke
				(width 0.1524)
				(type default)
			)
			(layer "F.SilkS")
		)
		(fp_line
			(start 0.7874 0.4064)
			(end -0.7874 0.4064)
			(stroke
				(width 0.1524)
				(type default)
			)
			(layer "F.SilkS")
		)
		(fp_line
			(start -0.7874 0.4064)
			(end -0.7874 -0.4064)
			(stroke
				(width 0.1524)
				(type default)
			)
			(layer "F.SilkS")
		)
		(fp_line
			(start -0.12065 -0.305054)
			(end -0.12065 -0.2794)
			(stroke
				(width 0.1)
				(type default)
			)
			(layer "F.Fab")
		)
		(fp_line
			(start -0.67945 -0.305054)
			(end -0.12065 -0.305054)
			(stroke
				(width 0.1)
				(type default)
			)
			(layer "F.Fab")
		)
		(fp_line
			(start 0.67945 -0.3048)
			(end 0.67945 0.3048)
			(stroke
				(width 0.1)
				(type default)
			)
			(layer "F.Fab")
		)
		(fp_line
			(start 0.12065 -0.3048)
			(end 0.67945 -0.3048)
			(stroke
				(width 0.1)
				(type default)
			)
			(layer "F.Fab")
		)
		(fp_line
			(start 0.12065 -0.2794)
			(end 0.12065 -0.3048)
			(stroke
				(width 0.1)
				(type default)
			)
			(layer "F.Fab")
		)
		(fp_line
			(start -0.12065 -0.2794)
			(end 0.12065 -0.2794)
			(stroke
				(width 0.1)
				(type default)
			)
			(layer "F.Fab")
		)
		(fp_line
			(start 0.120396 0.2794)
			(end -0.12065 0.2794)
			(stroke
				(width 0.1)
				(type default)
			)
			(layer "F.Fab")
		)
		(fp_line
			(start -0.12065 0.2794)
			(end -0.12065 0.3048)
			(stroke
				(width 0.1)
				(type default)
			)
			(layer "F.Fab")
		)
		(fp_line
			(start 0.67945 0.3048)
			(end 0.120396 0.3048)
			(stroke
				(width 0.1)
				(type default)
			)
			(layer "F.Fab")
		)
		(fp_line
			(start 0.120396 0.3048)
			(end 0.120396 0.2794)
			(stroke
				(width 0.1)
				(type default)
			)
			(layer "F.Fab")
		)
		(fp_line
			(start -0.12065 0.3048)
			(end -0.67945 0.3048)
			(stroke
				(width 0.1)
				(type default)
			)
			(layer "F.Fab")
		)
		(fp_line
			(start -0.67945 0.3048)
			(end -0.67945 -0.305054)
			(stroke
				(width 0.1)
				(type default)
			)
			(layer "F.Fab")
		)
		(pad "1" smd circle
			(at -0.40005 0 90)
			(size 0 0)
			(layers "F.Cu" "F.Mask" "F.Paste")
			(net "PEX2_SPARE3")
		)
		(pad "2" smd circle
			(at 0.40005 0 90)
			(size 0 0)
			(layers "F.Cu" "F.Mask" "F.Paste")
			(net "P1V8_PEX")
		)
	)
	(footprint ""
		(layer "F.Cu")
		(at 346.950792 -240.691162 90)
		(property "Reference" "R3525"
			(at 0 0 90)
			(layer "F.SilkS")
			(hide yes)
			(effects
				(font
					(size 1.27 1.27)
				)
			)
		)
		(property "Value" ""
			(at 0 0 90)
			(layer "F.Fab")
			(effects
				(font
					(size 1.27 1.27)
				)
			)
		)
		(duplicate_pad_numbers_are_jumpers no)
		(fp_line
			(start 0.7874 -0.4064)
			(end 0.7874 0.4064)
			(stroke
				(width 0.1524)
				(type default)
			)
			(layer "F.SilkS")
		)
		(fp_line
			(start -0.7874 -0.4064)
			(end 0.7874 -0.4064)
			(stroke
				(width 0.1524)
				(type default)
			)
			(layer "F.SilkS")
		)
		(fp_line
			(start 0.7874 0.4064)
			(end -0.7874 0.4064)
			(stroke
				(width 0.1524)
				(type default)
			)
			(layer "F.SilkS")
		)
		(fp_line
			(start -0.7874 0.4064)
			(end -0.7874 -0.4064)
			(stroke
				(width 0.1524)
				(type default)
			)
			(layer "F.SilkS")
		)
		(fp_line
			(start -0.12065 -0.305054)
			(end -0.12065 -0.2794)
			(stroke
				(width 0.1)
				(type default)
			)
			(layer "F.Fab")
		)
		(fp_line
			(start -0.67945 -0.305054)
			(end -0.12065 -0.305054)
			(stroke
				(width 0.1)
				(type default)
			)
			(layer "F.Fab")
		)
		(fp_line
			(start 0.67945 -0.3048)
			(end 0.67945 0.3048)
			(stroke
				(width 0.1)
				(type default)
			)
			(layer "F.Fab")
		)
		(fp_line
			(start 0.12065 -0.3048)
			(end 0.67945 -0.3048)
			(stroke
				(width 0.1)
				(type default)
			)
			(layer "F.Fab")
		)
		(fp_line
			(start 0.12065 -0.2794)
			(end 0.12065 -0.3048)
			(stroke
				(width 0.1)
				(type default)
			)
			(layer "F.Fab")
		)
		(fp_line
			(start -0.12065 -0.2794)
			(end 0.12065 -0.2794)
			(stroke
				(width 0.1)
				(type default)
			)
			(layer "F.Fab")
		)
		(fp_line
			(start 0.120396 0.2794)
			(end -0.12065 0.2794)
			(stroke
				(width 0.1)
				(type default)
			)
			(layer "F.Fab")
		)
		(fp_line
			(start -0.12065 0.2794)
			(end -0.12065 0.3048)
			(stroke
				(width 0.1)
				(type default)
			)
			(layer "F.Fab")
		)
		(fp_line
			(start 0.67945 0.3048)
			(end 0.120396 0.3048)
			(stroke
				(width 0.1)
				(type default)
			)
			(layer "F.Fab")
		)
		(fp_line
			(start 0.120396 0.3048)
			(end 0.120396 0.2794)
			(stroke
				(width 0.1)
				(type default)
			)
			(layer "F.Fab")
		)
		(fp_line
			(start -0.12065 0.3048)
			(end -0.67945 0.3048)
			(stroke
				(width 0.1)
				(type default)
			)
			(layer "F.Fab")
		)
		(fp_line
			(start -0.67945 0.3048)
			(end -0.67945 -0.305054)
			(stroke
				(width 0.1)
				(type default)
			)
			(layer "F.Fab")
		)
		(pad "1" smd circle
			(at -0.40005 0 90)
			(size 0 0)
			(layers "F.Cu" "F.Mask" "F.Paste")
			(net "RST_SSD2_PERST_N")
		)
		(pad "2" smd circle
			(at 0.40005 0 90)
			(size 0 0)
			(layers "F.Cu" "F.Mask" "F.Paste")
			(net "RST_SSD2_PERST_R_N")
		)
	)
	(footprint ""
		(layer "F.Cu")
		(at 115.847114 -262.322564 -90)
		(property "Reference" "PJ6"
			(at 0 0 270)
			(layer "F.SilkS")
			(hide yes)
			(effects
				(font
					(size 1.27 1.27)
				)
			)
		)
		(property "Value" ""
			(at 0 0 270)
			(layer "F.Fab")
			(effects
				(font
					(size 1.27 1.27)
				)
			)
		)
		(duplicate_pad_numbers_are_jumpers no)
		(pad "1" smd circle
			(at -0.7493 0)
			(size 0 0)
			(layers "F.Cu" "F.Mask" "F.Paste")
			(net "SH_P0V8_PEX1_VSEN1_L")
		)
		(pad "2" smd rect
			(at 0.7493 0 180)
			(size 0.7112 0.8128)
			(layers "F.Cu" "F.Mask" "F.Paste")
			(net "SH_P0V8_PEX1_VSEN1_R")
		)
		(zone
			(layer "F.Cu")
			(hatch none 0.5)
			(connect_pads
				(clearance 0)
			)
			(min_thickness 0.25)
			(keepout
				(tracks allowed)
				(vias not_allowed)
				(pads allowed)
				(copperpour not_allowed)
				(footprints allowed)
			)
			(placement
				(enabled no)
				(sheetname "")
			)
			(fill
				(thermal_gap 0.5)
				(thermal_bridge_width 0.5)
				(island_removal_mode 0)
			)
			(polygon
				(pts
					(xy 115.435888 -261.116064) (xy 116.253514 -261.116064) (xy 116.253514 -263.503664) (xy 115.435888 -263.503664)
				)
			)
		)
	)
	(footprint ""
		(layer "F.Cu")
		(at 273.115024 18.035524)
		(property "Reference" "DE03F_2"
			(at -3.6068 -2.962148 0)
			(unlocked yes)
			(layer "F.SilkS")
			(effects
				(font
					(size 0.7874 0.5842)
					(thickness 0.1524)
				)
				(justify left)
			)
		)
		(property "Value" ""
			(at 0 0 0)
			(layer "F.Fab")
			(effects
				(font
					(size 1.27 1.27)
				)
			)
		)
		(duplicate_pad_numbers_are_jumpers no)
		(fp_line
			(start -1.2192 -2.1082)
			(end 1.2192 -2.1082)
			(stroke
				(width 0.1524)
				(type default)
			)
			(layer "F.SilkS")
		)
		(fp_line
			(start -1.2192 2.1082)
			(end -1.2192 -2.1082)
			(stroke
				(width 0.1524)
				(type default)
			)
			(layer "F.SilkS")
		)
		(fp_line
			(start 1.2192 -2.1082)
			(end 1.2192 2.1082)
			(stroke
				(width 0.1524)
				(type default)
			)
			(layer "F.SilkS")
		)
		(fp_line
			(start 1.2192 2.1082)
			(end -1.2192 2.1082)
			(stroke
				(width 0.1524)
				(type default)
			)
			(layer "F.SilkS")
		)
		(pad "" np_thru_hole circle
			(at -2.8829 -1.27 270)
			(size 1.0414 1.0414)
			(drill 1.0414)
			(layers "*.Cu" "*.Mask")
			(clearance 0.381)
			(thermal_gap 0.381)
		)
		(pad "" np_thru_hole circle
			(at -2.8829 1.27 270)
			(size 1.0414 1.0414)
			(drill 1.0414)
			(layers "*.Cu" "*.Mask")
			(clearance 0.381)
			(thermal_gap 0.381)
		)
		(pad "" np_thru_hole circle
			(at 3.4671 -1.27 270)
			(size 1.0414 1.0414)
			(drill 1.0414)
			(layers "*.Cu" "*.Mask")
			(clearance 0.381)
			(thermal_gap 0.381)
		)
		(pad "" np_thru_hole circle
			(at 3.4671 1.27 270)
			(size 1.0414 1.0414)
			(drill 1.0414)
			(layers "*.Cu" "*.Mask")
			(clearance 0.381)
			(thermal_gap 0.381)
		)
		(pad "1" smd rect
			(at 0.8255 -0.249936 270)
			(size 0.3048 0.508)
			(layers "F.Cu" "F.Mask" "F.Paste")
			(net "85_5INCH_IN1_DP")
		)
		(pad "2" smd rect
			(at 0.8255 0.249936 270)
			(size 0.3048 0.508)
			(layers "F.Cu" "F.Mask" "F.Paste")
			(net "85_5INCH_IN1_DN")
		)
		(pad "3" smd circle
			(at 0 0)
			(size 0 0)
			(layers "F.Cu" "F.Mask" "F.Paste")
			(net "COUPON_GND2")
		)
		(zone
			(layer "F.Cu")
			(hatch none 0.5)
			(connect_pads
				(clearance 0)
			)
			(min_thickness 0.25)
			(keepout
				(tracks not_allowed)
				(vias allowed)
				(pads allowed)
				(copperpour not_allowed)
				(footprints allowed)
			)
			(placement
				(enabled no)
				(sheetname "")
			)
			(fill
				(thermal_gap 0.5)
				(thermal_bridge_width 0.5)
				(island_removal_mode 0)
			)
			(polygon
				(pts
					(xy 274.232624 17.486884) (xy 274.232624 17.582388) (xy 273.635724 17.582388) (xy 273.635724 17.988788)
					(xy 274.232624 17.988788) (xy 274.232624 18.08226) (xy 273.635724 18.08226) (xy 273.635724 18.48866)
					(xy 274.232624 18.48866) (xy 274.232624 18.584164) (xy 273.534124 18.584164) (xy 273.534124 17.486884)
				)
			)
		)
		(zone
			(layers "F.Cu" "B.Cu" "In1.Cu" "In2.Cu" "In3.Cu" "In4.Cu" "In5.Cu" "In6.Cu"
				"In7.Cu" "In8.Cu" "In9.Cu" "In10.Cu" "In11.Cu" "In12.Cu" "In13.Cu" "In14.Cu"
				"In15.Cu" "In16.Cu"
			)
			(hatch none 0.5)
			(connect_pads
				(clearance 0)
			)
			(min_thickness 0.25)
			(keepout
				(tracks not_allowed)
				(vias allowed)
				(pads allowed)
				(copperpour not_allowed)
				(footprints allowed)
			)
			(placement
				(enabled no)
				(sheetname "")
			)
			(fill
				(thermal_gap 0.5)
				(thermal_bridge_width 0.5)
				(island_removal_mode 0)
			)
			(polygon
				(pts
					(arc
						(start 271.159224 16.765524)
						(mid 269.305024 16.765524)
						(end 271.159224 16.765524)
					)
				)
			)
		)
		(zone
			(layers "F.Cu" "B.Cu" "In1.Cu" "In2.Cu" "In3.Cu" "In4.Cu" "In5.Cu" "In6.Cu"
				"In7.Cu" "In8.Cu" "In9.Cu" "In10.Cu" "In11.Cu" "In12.Cu" "In13.Cu" "In14.Cu"
				"In15.Cu" "In16.Cu"
			)
			(hatch none 0.5)
			(connect_pads
				(clearance 0)
			)
			(min_thickness 0.25)
			(keepout
				(tracks not_allowed)
				(vias allowed)
				(pads allowed)
				(copperpour not_allowed)
				(footprints allowed)
			)
			(placement
				(enabled no)
				(sheetname "")
			)
			(fill
				(thermal_gap 0.5)
				(thermal_bridge_width 0.5)
				(island_removal_mode 0)
			)
			(polygon
				(pts
					(arc
						(start 271.159224 19.305524)
						(mid 269.305024 19.305524)
						(end 271.159224 19.305524)
					)
				)
			)
		)
		(zone
			(layers "F.Cu" "B.Cu" "In1.Cu" "In2.Cu" "In3.Cu" "In4.Cu" "In5.Cu" "In6.Cu"
				"In7.Cu" "In8.Cu" "In9.Cu" "In10.Cu" "In11.Cu" "In12.Cu" "In13.Cu" "In14.Cu"
				"In15.Cu" "In16.Cu"
			)
			(hatch none 0.5)
			(connect_pads
				(clearance 0)
			)
			(min_thickness 0.25)
			(keepout
				(tracks not_allowed)
				(vias allowed)
				(pads allowed)
				(copperpour not_allowed)
				(footprints allowed)
			)
			(placement
				(enabled no)
				(sheetname "")
			)
			(fill
				(thermal_gap 0.5)
				(thermal_bridge_width 0.5)
				(island_removal_mode 0)
			)
			(polygon
				(pts
					(arc
						(start 277.509224 16.765524)
						(mid 275.655024 16.765524)
						(end 277.509224 16.765524)
					)
				)
			)
		)
		(zone
			(layers "F.Cu" "B.Cu" "In1.Cu" "In2.Cu" "In3.Cu" "In4.Cu" "In5.Cu" "In6.Cu"
				"In7.Cu" "In8.Cu" "In9.Cu" "In10.Cu" "In11.Cu" "In12.Cu" "In13.Cu" "In14.Cu"
				"In15.Cu" "In16.Cu"
			)
			(hatch none 0.5)
			(connect_pads
				(clearance 0)
			)
			(min_thickness 0.25)
			(keepout
				(tracks not_allowed)
				(vias allowed)
				(pads allowed)
				(copperpour not_allowed)
				(footprints allowed)
			)
			(placement
				(enabled no)
				(sheetname "")
			)
			(fill
				(thermal_gap 0.5)
				(thermal_bridge_width 0.5)
				(island_removal_mode 0)
			)
			(polygon
				(pts
					(arc
						(start 277.509224 19.305524)
						(mid 275.655024 19.305524)
						(end 277.509224 19.305524)
					)
				)
			)
		)
	)
)
